(kicad_pcb
	(version 20260206)
	(generator "pcbnew")
	(generator_version "10.0")
	(general
		(thickness 1.6)
		(legacy_teardrops no)
	)
	(paper "A4")
	(title_block
		(title "timecard-production-celestica-r4006 — R4006-B0001-02_R01.brd")
		(comment 1 "Time Appliance Project (Time Card) / footprints 653-657 of 1113")
	)
	(layers
		(0 "F.Cu" signal "TOP")
		(4 "In1.Cu" signal "L02_GND1")
		(6 "In2.Cu" signal "L03_SIG1")
		(8 "In3.Cu" signal "L04_GND2")
		(10 "In4.Cu" signal "L05_VCC1")
		(12 "In5.Cu" signal "L06_VCC2")
		(14 "In6.Cu" signal "L07_GND3")
		(16 "In7.Cu" signal "L08_SIG2")
		(18 "In8.Cu" signal "L09_GND4")
		(2 "B.Cu" signal "BOTTOM")
		(9 "F.Adhes" user "F.Adhesive")
		(11 "B.Adhes" user "B.Adhesive")
		(13 "F.Paste" user "Package Geometry/Pastemask Top")
		(15 "B.Paste" user "Package Geometry/Pastemask Bottom")
		(5 "F.SilkS" user "Ref Des/Silkscreen Top")
		(7 "B.SilkS" user "Ref Des/Silkscreen Bottom")
		(1 "F.Mask" user "Board Geometry/Soldermask Top")
		(3 "B.Mask" user "Board Geometry/Soldermask Bottom")
		(17 "Dwgs.User" user "User.Drawings")
		(19 "Cmts.User" user "User.Comments")
		(21 "Eco1.User" user "User.Eco1")
		(23 "Eco2.User" user "User.Eco2")
		(25 "Edge.Cuts" user "Board Geometry/Outline")
		(27 "Margin" user)
		(31 "F.CrtYd" user "Package Geometry/Place Bound Top")
		(29 "B.CrtYd" user "Package Geometry/Place Bound Bottom")
		(35 "F.Fab" user "Ref Des/Assembly Top")
		(33 "B.Fab" user "Ref Des/Assembly Bottom")
	)
	(footprint ""
		(layer "F.Cu")
		(at 115.062 -83.058)
		(property "Reference" "C97"
			(at 1.016 -1.10363 0)
			(unlocked yes)
			(layer "F.SilkS")
			(effects
				(font
					(size 0.7874 0.5842)
					(thickness 0.1524)
				)
			)
		)
		(property "Value" "VAL*"
			(at 0.0762 2.067306 0)
			(unlocked yes)
			(layer "F.Fab")
			(hide yes)
			(effects
				(font
					(size 0.7874 0.5842)
					(thickness 0.1524)
				)
			)
		)
		(property "Tolerance" "TOL*"
			(at 0.0762 3.032506 0)
			(unlocked yes)
			(layer "Cmts.User")
			(hide yes)
			(effects
				(font
					(size 0.7874 0.5842)
					(thickness 0.1524)
				)
			)
		)
		(property "User Part Number" "PARTNUM*"
			(at 0.1016 4.023106 0)
			(unlocked yes)
			(layer "Cmts.User")
			(hide yes)
			(effects
				(font
					(size 0.7874 0.5842)
					(thickness 0.1524)
				)
			)
		)
		(property "Device Type" "CAPACITOR-G105-0B104-EK,0.1UF,A"
			(at 0.0508 1.127506 0)
			(unlocked yes)
			(layer "F.Fab")
			(hide yes)
			(effects
				(font
					(size 0.7874 0.5842)
					(thickness 0.1524)
				)
			)
		)
		(duplicate_pad_numbers_are_jumpers no)
		(fp_line
			(start -1.143 -0.5588)
			(end -1.143 0.5588)
			(stroke
				(width 0.1)
				(type default)
			)
			(layer "F.SilkS")
		)
		(fp_line
			(start -1.143 0.5588)
			(end 1.143 0.5588)
			(stroke
				(width 0.1)
				(type default)
			)
			(layer "F.SilkS")
		)
		(fp_line
			(start 1.143 -0.5588)
			(end -1.143 -0.5588)
			(stroke
				(width 0.1)
				(type default)
			)
			(layer "F.SilkS")
		)
		(fp_line
			(start 1.143 0.5588)
			(end 1.143 -0.5588)
			(stroke
				(width 0.1)
				(type default)
			)
			(layer "F.SilkS")
		)
		(fp_poly
			(pts
				(xy -1.143 0.5588) (xy 1.143 0.5588) (xy 1.143 -0.5588) (xy -1.143 -0.5588)
			)
			(stroke
				(width 0)
				(type default)
			)
			(fill no)
			(layer "F.CrtYd")
		)
		(fp_line
			(start -0.508 -0.3048)
			(end -0.508 0.3048)
			(stroke
				(width 0.1)
				(type default)
			)
			(layer "F.Fab")
		)
		(fp_line
			(start -0.508 0.3048)
			(end 0.508 0.3048)
			(stroke
				(width 0.1)
				(type default)
			)
			(layer "F.Fab")
		)
		(fp_line
			(start 0.508 -0.3048)
			(end -0.508 -0.3048)
			(stroke
				(width 0.1)
				(type default)
			)
			(layer "F.Fab")
		)
		(fp_line
			(start 0.508 0.3048)
			(end 0.508 -0.3048)
			(stroke
				(width 0.1)
				(type default)
			)
			(layer "F.Fab")
		)
		(pad "1" smd rect
			(at -0.5334 0)
			(size 0.7112 0.6096)
			(layers "F.Cu" "F.Mask" "F.Paste")
			(net "XP3R3V_FPGA")
		)
		(pad "2" smd rect
			(at 0.5334 0)
			(size 0.7112 0.6096)
			(layers "F.Cu" "F.Mask" "F.Paste")
			(net "SG")
		)
		(zone
			(layer "F.Cu")
			(hatch none 0.5)
			(connect_pads
				(clearance 0)
			)
			(min_thickness 0.25)
			(keepout
				(tracks allowed)
				(vias not_allowed)
				(pads allowed)
				(copperpour not_allowed)
				(footprints allowed)
			)
			(placement
				(enabled no)
				(sheetname "")
			)
			(fill
				(thermal_gap 0.5)
				(thermal_bridge_width 0.5)
				(island_removal_mode 0)
			)
			(polygon
				(pts
					(xy 114.9858 -82.7532) (xy 115.1382 -82.7532) (xy 115.1382 -83.3628) (xy 114.9858 -83.3628)
				)
			)
		)
		(zone
			(layer "F.Cu")
			(hatch none 0.5)
			(connect_pads
				(clearance 0)
			)
			(min_thickness 0.25)
			(keepout
				(tracks not_allowed)
				(vias allowed)
				(pads allowed)
				(copperpour not_allowed)
				(footprints allowed)
			)
			(placement
				(enabled no)
				(sheetname "")
			)
			(fill
				(thermal_gap 0.5)
				(thermal_bridge_width 0.5)
				(island_removal_mode 0)
			)
			(polygon
				(pts
					(xy 114.9858 -82.7532) (xy 115.1382 -82.7532) (xy 115.1382 -83.3628) (xy 114.9858 -83.3628)
				)
			)
		)
	)
	(footprint ""
		(layer "F.Cu")
		(at 4.073906 -18.10004)
		(property "Reference" "J2"
			(at 4.943094 3.40741 0)
			(unlocked yes)
			(layer "F.SilkS")
			(effects
				(font
					(size 0.7874 0.5842)
					(thickness 0.1524)
				)
			)
		)
		(property "Value" ""
			(at 0 0 0)
			(layer "F.Fab")
			(effects
				(font
					(size 1.27 1.27)
				)
			)
		)
		(property "Device Type" "CONN_JACK_1P_GH4_S_TH-G200-130A"
			(at -5.098288 5.899912 0)
			(unlocked yes)
			(layer "F.Fab")
			(hide yes)
			(effects
				(font
					(size 0.7874 0.5842)
					(thickness 0.1524)
				)
			)
		)
		(property "User Part Number" "PARTNUM*"
			(at -5.098288 7.093712 0)
			(unlocked yes)
			(layer "Cmts.User")
			(hide yes)
			(effects
				(font
					(size 0.7874 0.5842)
					(thickness 0.1524)
				)
			)
		)
		(duplicate_pad_numbers_are_jumpers no)
		(fp_line
			(start -13.953998 -3.937)
			(end 3.937 -3.937)
			(stroke
				(width 0.1)
				(type default)
			)
			(layer "F.SilkS")
		)
		(fp_line
			(start -13.953998 3.937)
			(end -13.953998 -3.937)
			(stroke
				(width 0.1)
				(type default)
			)
			(layer "F.SilkS")
		)
		(fp_line
			(start 3.937 -3.937)
			(end 3.937 3.937)
			(stroke
				(width 0.1)
				(type default)
			)
			(layer "F.SilkS")
		)
		(fp_line
			(start 3.937 3.937)
			(end -13.953998 3.937)
			(stroke
				(width 0.1)
				(type default)
			)
			(layer "F.SilkS")
		)
		(fp_rect
			(start -8.763 8.763)
			(end 8.763 -8.763)
			(stroke
				(width 0)
				(type default)
			)
			(fill no)
			(layer "B.CrtYd")
		)
		(fp_rect
			(start -14.207998 4.191)
			(end 4.191 -4.191)
			(stroke
				(width 0)
				(type default)
			)
			(fill no)
			(layer "F.CrtYd")
		)
		(fp_line
			(start -13.699998 -3.599942)
			(end 3.599942 -3.599942)
			(stroke
				(width 0.1)
				(type default)
			)
			(layer "F.Fab")
		)
		(fp_line
			(start -13.699998 3.599942)
			(end -13.699998 -3.599942)
			(stroke
				(width 0.1)
				(type default)
			)
			(layer "F.Fab")
		)
		(fp_line
			(start 3.599942 -3.599942)
			(end 3.599942 3.599942)
			(stroke
				(width 0.1)
				(type default)
			)
			(layer "F.Fab")
		)
		(fp_line
			(start 3.599942 3.599942)
			(end -13.699998 3.599942)
			(stroke
				(width 0.1)
				(type default)
			)
			(layer "F.Fab")
		)
		(fp_text user "GH3"
			(at -1.660906 4.55041 0)
			(unlocked yes)
			(layer "F.SilkS")
			(effects
				(font
					(size 0.7874 0.5842)
					(thickness 0.1524)
				)
			)
		)
		(fp_text user "GH1"
			(at -0.263906 -4.34721 0)
			(unlocked yes)
			(layer "F.SilkS")
			(effects
				(font
					(size 0.635 0.4064)
					(thickness 0.1524)
				)
			)
		)
		(fp_text user "GH2"
			(at 2.276094 -4.34721 0)
			(unlocked yes)
			(layer "F.SilkS")
			(effects
				(font
					(size 0.635 0.4064)
					(thickness 0.1524)
				)
			)
		)
		(fp_text user "GH4"
			(at 2.784094 4.67741 0)
			(unlocked yes)
			(layer "F.SilkS")
			(effects
				(font
					(size 0.7874 0.5842)
					(thickness 0.1524)
				)
			)
		)
		(fp_text user "1"
			(at 4.191 -0.35433 0)
			(unlocked yes)
			(layer "F.SilkS")
			(effects
				(font
					(size 0.7874 0.5842)
					(thickness 0.1524)
				)
				(justify left)
			)
		)
		(fp_text user "GH3"
			(at -2.803906 4.187698 0)
			(unlocked yes)
			(layer "F.Fab")
			(effects
				(font
					(size 0.7874 0.5842)
					(thickness 0.1524)
				)
			)
		)
		(fp_text user "GH1"
			(at -2.295906 -4.08559 0)
			(unlocked yes)
			(layer "F.Fab")
			(effects
				(font
					(size 0.7874 0.5842)
					(thickness 0.1524)
				)
			)
		)
		(fp_text user "GH2"
			(at 2.530094 -4.08559 0)
			(unlocked yes)
			(layer "F.Fab")
			(effects
				(font
					(size 0.7874 0.5842)
					(thickness 0.1524)
				)
			)
		)
		(fp_text user "GH4"
			(at 2.54 4.64947 0)
			(unlocked yes)
			(layer "F.Fab")
			(effects
				(font
					(size 0.7874 0.5842)
					(thickness 0.1524)
				)
			)
		)
		(fp_text user "1"
			(at 4.191 -0.35433 0)
			(unlocked yes)
			(layer "F.Fab")
			(effects
				(font
					(size 0.7874 0.5842)
					(thickness 0.1524)
				)
				(justify left)
			)
		)
		(pad "1" thru_hole circle
			(at 0 0)
			(size 2.1844 2.1844)
			(drill 1.4986)
			(layers "*.Cu" "*.Mask")
			(remove_unused_layers no)
			(net "SMA4_SIG_IO_CONN")
			(padstack
				(mode front_inner_back)
				(layer "Inner"
					(shape circle)
					(size 2.1844 2.1844)
					(clearance -0.0508)
				)
				(layer "B.Cu"
					(shape circle)
					(size 2.1844 2.1844)
				)
			)
		)
		(pad "GH1" thru_hole circle
			(at -2.54 -2.54)
			(size 2.286 2.286)
			(drill 1.6002)
			(layers "*.Cu" "*.Mask")
			(remove_unused_layers no)
			(net "SG")
			(padstack
				(mode front_inner_back)
				(layer "Inner"
					(shape circle)
					(size 2.286 2.286)
					(clearance -0.0508)
				)
				(layer "B.Cu"
					(shape circle)
					(size 2.286 2.286)
				)
			)
		)
		(pad "GH2" thru_hole circle
			(at 2.54 -2.54)
			(size 2.286 2.286)
			(drill 1.6002)
			(layers "*.Cu" "*.Mask")
			(remove_unused_layers no)
			(net "SG")
			(padstack
				(mode front_inner_back)
				(layer "Inner"
					(shape circle)
					(size 2.286 2.286)
					(clearance -0.0508)
				)
				(layer "B.Cu"
					(shape circle)
					(size 2.286 2.286)
				)
			)
		)
		(pad "GH3" thru_hole circle
			(at -2.54 2.54)
			(size 2.286 2.286)
			(drill 1.6002)
			(layers "*.Cu" "*.Mask")
			(remove_unused_layers no)
			(net "SG")
			(padstack
				(mode front_inner_back)
				(layer "Inner"
					(shape circle)
					(size 2.286 2.286)
					(clearance -0.0508)
				)
				(layer "B.Cu"
					(shape circle)
					(size 2.286 2.286)
				)
			)
		)
		(pad "GH4" thru_hole circle
			(at 2.54 2.54)
			(size 2.286 2.286)
			(drill 1.6002)
			(layers "*.Cu" "*.Mask")
			(remove_unused_layers no)
			(net "SG")
			(padstack
				(mode front_inner_back)
				(layer "Inner"
					(shape circle)
					(size 2.286 2.286)
					(clearance -0.0508)
				)
				(layer "B.Cu"
					(shape circle)
					(size 2.286 2.286)
				)
			)
		)
	)
	(footprint ""
		(layer "F.Cu")
		(at 20.193 -78.359)
		(property "Reference" "TP6"
			(at 0.29337 3.2385 90)
			(unlocked yes)
			(layer "F.SilkS")
			(effects
				(font
					(size 0.7874 0.5842)
					(thickness 0.1524)
				)
				(justify left)
			)
		)
		(property "Value" ""
			(at 0 0 0)
			(layer "F.Fab")
			(effects
				(font
					(size 1.27 1.27)
				)
			)
		)
		(property "Device Type" "TP_PIONT-TP010CT020B030_PTH-TPA"
			(at -1.341882 0.996696 0)
			(unlocked yes)
			(layer "F.Fab")
			(hide yes)
			(effects
				(font
					(size 0.7874 0.5842)
					(thickness 0.1524)
				)
				(justify left)
			)
		)
		(duplicate_pad_numbers_are_jumpers no)
		(fp_poly
			(pts
				(arc
					(start 0.889 0)
					(mid -0.889 0)
					(end 0.889 0)
				)
			)
			(stroke
				(width 0)
				(type default)
			)
			(fill no)
			(layer "B.CrtYd")
		)
		(fp_poly
			(pts
				(arc
					(start 0.889 0)
					(mid -0.889 0)
					(end 0.889 0)
				)
			)
			(stroke
				(width 0)
				(type default)
			)
			(fill no)
			(layer "F.CrtYd")
		)
		(pad "1" thru_hole circle
			(at 0 0)
			(size 0.508 0.508)
			(drill 0.254)
			(layers "*.Cu" "*.Mask")
			(remove_unused_layers no)
			(net "UNNAMED_524_FT4232HLREELQFP64_1")
			(clearance 0.1016)
			(padstack
				(mode front_inner_back)
				(layer "Inner"
					(shape circle)
					(size 0.508 0.508)
					(clearance 0.1016)
				)
				(layer "B.Cu"
					(shape circle)
					(size 0.762 0.762)
					(clearance -0.0254)
				)
			)
		)
	)
	(footprint ""
		(layer "F.Cu")
		(at 124.1806 -68.7578 -90)
		(property "Reference" "R141"
			(at 2.5908 0.18923 90)
			(unlocked yes)
			(layer "F.SilkS")
			(effects
				(font
					(size 0.7874 0.5842)
					(thickness 0.1524)
				)
			)
		)
		(property "Value" "VAL*"
			(at 0.02032 2.13233 270)
			(unlocked yes)
			(layer "F.Fab")
			(hide yes)
			(effects
				(font
					(size 0.7874 0.5842)
					(thickness 0.1524)
				)
			)
		)
		(property "Device Type" "RESISTOR-G155-100R0-J0,0OHM,-"
			(at 0.008382 1.210564 270)
			(unlocked yes)
			(layer "F.Fab")
			(hide yes)
			(effects
				(font
					(size 0.7874 0.5842)
					(thickness 0.1524)
				)
			)
		)
		(property "User Part Number" "PARTNUM*"
			(at 0.02032 4.024884 270)
			(unlocked yes)
			(layer "Cmts.User")
			(hide yes)
			(effects
				(font
					(size 0.7874 0.5842)
					(thickness 0.1524)
				)
			)
		)
		(property "Tolerance" "TOL*"
			(at 0.044704 3.05435 270)
			(unlocked yes)
			(layer "Cmts.User")
			(hide yes)
			(effects
				(font
					(size 0.7874 0.5842)
					(thickness 0.1524)
				)
			)
		)
		(duplicate_pad_numbers_are_jumpers no)
		(fp_line
			(start -1.143 0.5588)
			(end 1.143 0.5588)
			(stroke
				(width 0.1)
				(type default)
			)
			(layer "F.SilkS")
		)
		(fp_line
			(start 1.143 0.5588)
			(end 1.143 -0.5588)
			(stroke
				(width 0.1)
				(type default)
			)
			(layer "F.SilkS")
		)
		(fp_line
			(start -1.143 -0.5588)
			(end -1.143 0.5588)
			(stroke
				(width 0.1)
				(type default)
			)
			(layer "F.SilkS")
		)
		(fp_line
			(start 1.143 -0.5588)
			(end -1.143 -0.5588)
			(stroke
				(width 0.1)
				(type default)
			)
			(layer "F.SilkS")
		)
		(fp_rect
			(start 1.143 0.5588)
			(end -1.143 -0.5588)
			(stroke
				(width 0)
				(type default)
			)
			(fill no)
			(layer "F.CrtYd")
		)
		(fp_line
			(start -0.508 0.3048)
			(end 0.508 0.3048)
			(stroke
				(width 0.1)
				(type default)
			)
			(layer "F.Fab")
		)
		(fp_line
			(start 0.508 0.3048)
			(end 0.508 -0.3048)
			(stroke
				(width 0.1)
				(type default)
			)
			(layer "F.Fab")
		)
		(fp_line
			(start -0.508 -0.3048)
			(end -0.508 0.3048)
			(stroke
				(width 0.1)
				(type default)
			)
			(layer "F.Fab")
		)
		(fp_line
			(start 0.508 -0.3048)
			(end -0.508 -0.3048)
			(stroke
				(width 0.1)
				(type default)
			)
			(layer "F.Fab")
		)
		(pad "1" smd rect
			(at -0.5334 0 270)
			(size 0.7112 0.6096)
			(layers "F.Cu" "F.Mask" "F.Paste")
			(net "XP1R2V_FPGA_PG")
		)
		(pad "2" smd rect
			(at 0.5334 0 270)
			(size 0.7112 0.6096)
			(layers "F.Cu" "F.Mask" "F.Paste")
			(net "XP1R8V_EN_R")
		)
		(zone
			(layer "F.Cu")
			(hatch none 0.5)
			(connect_pads
				(clearance 0)
			)
			(min_thickness 0.25)
			(keepout
				(tracks allowed)
				(vias not_allowed)
				(pads allowed)
				(copperpour not_allowed)
				(footprints allowed)
			)
			(placement
				(enabled no)
				(sheetname "")
			)
			(fill
				(thermal_gap 0.5)
				(thermal_bridge_width 0.5)
				(island_removal_mode 0)
			)
			(polygon
				(pts
					(xy 123.8758 -68.6816) (xy 124.4854 -68.6816) (xy 124.4854 -68.834) (xy 123.8758 -68.834)
				)
			)
		)
	)
	(footprint ""
		(layer "F.Cu")
		(at 124.587 -41.402 180)
		(property "Reference" "R93"
			(at -2.667 1.48463 0)
			(unlocked yes)
			(layer "F.SilkS")
			(effects
				(font
					(size 0.7874 0.5842)
					(thickness 0.1524)
				)
			)
		)
		(property "Value" "VAL*"
			(at 0.02032 2.13233 180)
			(unlocked yes)
			(layer "F.Fab")
			(hide yes)
			(effects
				(font
					(size 0.7874 0.5842)
					(thickness 0.1524)
				)
			)
		)
		(property "Tolerance" "TOL*"
			(at 0.044704 3.05435 180)
			(unlocked yes)
			(layer "Cmts.User")
			(hide yes)
			(effects
				(font
					(size 0.7874 0.5842)
					(thickness 0.1524)
				)
			)
		)
		(property "User Part Number" "PARTNUM*"
			(at 0.02032 4.024884 180)
			(unlocked yes)
			(layer "Cmts.User")
			(hide yes)
			(effects
				(font
					(size 0.7874 0.5842)
					(thickness 0.1524)
				)
			)
		)
		(property "Device Type" "RESISTOR-G155-133R0-01,33OHM,1%"
			(at 0.008382 1.210564 180)
			(unlocked yes)
			(layer "F.Fab")
			(hide yes)
			(effects
				(font
					(size 0.7874 0.5842)
					(thickness 0.1524)
				)
			)
		)
		(duplicate_pad_numbers_are_jumpers no)
		(fp_line
			(start 1.143 0.5588)
			(end 1.143 -0.5588)
			(stroke
				(width 0.1)
				(type default)
			)
			(layer "F.SilkS")
		)
		(fp_line
			(start 1.143 -0.5588)
			(end -1.143 -0.5588)
			(stroke
				(width 0.1)
				(type default)
			)
			(layer "F.SilkS")
		)
		(fp_line
			(start -1.143 0.5588)
			(end 1.143 0.5588)
			(stroke
				(width 0.1)
				(type default)
			)
			(layer "F.SilkS")
		)
		(fp_line
			(start -1.143 -0.5588)
			(end -1.143 0.5588)
			(stroke
				(width 0.1)
				(type default)
			)
			(layer "F.SilkS")
		)
		(fp_rect
			(start 1.143 -0.5588)
			(end -1.143 0.5588)
			(stroke
				(width 0)
				(type default)
			)
			(fill no)
			(layer "F.CrtYd")
		)
		(fp_line
			(start 0.508 0.3048)
			(end 0.508 -0.3048)
			(stroke
				(width 0.1)
				(type default)
			)
			(layer "F.Fab")
		)
		(fp_line
			(start 0.508 -0.3048)
			(end -0.508 -0.3048)
			(stroke
				(width 0.1)
				(type default)
			)
			(layer "F.Fab")
		)
		(fp_line
			(start -0.508 0.3048)
			(end 0.508 0.3048)
			(stroke
				(width 0.1)
				(type default)
			)
			(layer "F.Fab")
		)
		(fp_line
			(start -0.508 -0.3048)
			(end -0.508 0.3048)
			(stroke
				(width 0.1)
				(type default)
			)
			(layer "F.Fab")
		)
		(pad "1" smd rect
			(at -0.5334 0 180)
			(size 0.7112 0.6096)
			(layers "F.Cu" "F.Mask" "F.Paste")
			(net "R_MAC_BITEOUT")
		)
		(pad "2" smd rect
			(at 0.5334 0 180)
			(size 0.7112 0.6096)
			(layers "F.Cu" "F.Mask" "F.Paste")
			(net "FPGA_IN_MAC_BITEOUT")
		)
		(zone
			(layer "F.Cu")
			(hatch none 0.5)
			(connect_pads
				(clearance 0)
			)
			(min_thickness 0.25)
			(keepout
				(tracks allowed)
				(vias not_allowed)
				(pads allowed)
				(copperpour not_allowed)
				(footprints allowed)
			)
			(placement
				(enabled no)
				(sheetname "")
			)
			(fill
				(thermal_gap 0.5)
				(thermal_bridge_width 0.5)
				(island_removal_mode 0)
			)
			(polygon
				(pts
					(xy 124.5108 -41.0972) (xy 124.6632 -41.0972) (xy 124.6632 -41.7068) (xy 124.5108 -41.7068)
				)
			)
		)
	)
)
